# T6G (Grand Teton) — schematic netlist excerpt (pin names and nets, part order shuffled) for the footprints in the layout excerpt that follows; sources: Cadence DE-HDL packaged netlist, KiCad conversion of 04192023_DAF0TMB3IC0_F0TG_MB_C_brd_V02_OCP.brd

R4641  Q_RES  243 1% CHIP  pkg 1206LF  page 188 : A = P5V ; B = VR_P5V_EN_D
PR6542  Q_RES  0 5% CHIP  pkg 0402LF  page 364 : A = NC_P0V9_RETIMER_CPU1_IMON6 ; B = GND
PR437  Q_RES  0 5% CHIP  pkg 0402LF  page 210 : A = NC_PVDDCR_CPU0_P1_IMON9 ; B = GND

(kicad_pcb
	(version 20260206)
	(generator "pcbnew")
	(generator_version "10.0")
	(general
		(thickness 1.6)
		(legacy_teardrops no)
	)
	(paper "A4")
	(title_block
		(title "04192023_DAF0TMB3IC0_F0TG_MB_C_brd_V02_OCP.brd")
		(comment 1 "Grand Teton / footprints 5180-5182 of 8354")
	)
	(layers
		(0 "F.Cu" signal "TOP")
		(4 "In1.Cu" signal "GND")
		(6 "In2.Cu" signal "IN1")
		(8 "In3.Cu" signal "GND1")
		(10 "In4.Cu" signal "IN2")
		(12 "In5.Cu" signal "GND2")
		(14 "In6.Cu" signal "IN3")
		(16 "In7.Cu" signal "GND3")
		(18 "In8.Cu" signal "VCC")
		(20 "In9.Cu" signal "VCC1")
		(22 "In10.Cu" signal "GND4")
		(24 "In11.Cu" signal "IN4")
		(26 "In12.Cu" signal "GND5")
		(28 "In13.Cu" signal "IN5")
		(30 "In14.Cu" signal "GND6")
		(32 "In15.Cu" signal "IN6")
		(34 "In16.Cu" signal "GND7")
		(2 "B.Cu" signal "BOTTOM")
		(9 "F.Adhes" user "F.Adhesive")
		(11 "B.Adhes" user "B.Adhesive")
		(13 "F.Paste" user "Package Geometry/Pastemask Top")
		(15 "B.Paste" user "Package Geometry/Pastemask Bottom")
		(5 "F.SilkS" user "Ref Des/Silkscreen Top")
		(7 "B.SilkS" user "Ref Des/Silkscreen Bottom")
		(1 "F.Mask" user "Board Geometry/Soldermask Top")
		(3 "B.Mask" user "Board Geometry/Soldermask Bottom")
		(17 "Dwgs.User" user "User.Drawings")
		(19 "Cmts.User" user "User.Comments")
		(21 "Eco1.User" user "User.Eco1")
		(23 "Eco2.User" user "User.Eco2")
		(25 "Edge.Cuts" user "Board Geometry/Outline")
		(27 "Margin" user)
		(31 "F.CrtYd" user "Package Geometry/Place Bound Top")
		(29 "B.CrtYd" user "Package Geometry/Place Bound Bottom")
		(35 "F.Fab" user "Ref Des/Assembly Top")
		(33 "B.Fab" user "Ref Des/Assembly Bottom")
	)
	(footprint ""
		(layer "B.Cu")
		(at 98.918522 -150.698962 -90)
		(property "Reference" "PR437"
			(at 0 0 90)
			(layer "B.SilkS")
			(hide yes)
			(effects
				(font
					(size 1.27 1.27)
				)
				(justify mirror)
			)
		)
		(property "Value" ""
			(at 0 0 90)
			(layer "B.Fab")
			(effects
				(font
					(size 1.27 1.27)
				)
				(justify mirror)
			)
		)
		(duplicate_pad_numbers_are_jumpers no)
		(fp_line
			(start -0.7874 0.4064)
			(end 0.7874 0.4064)
			(stroke
				(width 0.1524)
				(type default)
			)
			(layer "B.SilkS")
		)
		(fp_line
			(start 0.7874 0.4064)
			(end 0.7874 -0.4064)
			(stroke
				(width 0.1524)
				(type default)
			)
			(layer "B.SilkS")
		)
		(fp_line
			(start -0.7874 -0.4064)
			(end -0.7874 0.4064)
			(stroke
				(width 0.1524)
				(type default)
			)
			(layer "B.SilkS")
		)
		(fp_line
			(start 0.7874 -0.4064)
			(end -0.7874 -0.4064)
			(stroke
				(width 0.1524)
				(type default)
			)
			(layer "B.SilkS")
		)
		(fp_line
			(start -0.67945 0.3048)
			(end -0.120396 0.3048)
			(stroke
				(width 0.1)
				(type default)
			)
			(layer "B.Fab")
		)
		(fp_line
			(start -0.120396 0.3048)
			(end -0.120396 0.2794)
			(stroke
				(width 0.1)
				(type default)
			)
			(layer "B.Fab")
		)
		(fp_line
			(start 0.12065 0.3048)
			(end 0.67945 0.3048)
			(stroke
				(width 0.1)
				(type default)
			)
			(layer "B.Fab")
		)
		(fp_line
			(start 0.67945 0.3048)
			(end 0.67945 -0.305054)
			(stroke
				(width 0.1)
				(type default)
			)
			(layer "B.Fab")
		)
		(fp_line
			(start -0.120396 0.2794)
			(end 0.12065 0.2794)
			(stroke
				(width 0.1)
				(type default)
			)
			(layer "B.Fab")
		)
		(fp_line
			(start 0.12065 0.2794)
			(end 0.12065 0.3048)
			(stroke
				(width 0.1)
				(type default)
			)
			(layer "B.Fab")
		)
		(fp_line
			(start -0.12065 -0.2794)
			(end -0.12065 -0.3048)
			(stroke
				(width 0.1)
				(type default)
			)
			(layer "B.Fab")
		)
		(fp_line
			(start 0.12065 -0.2794)
			(end -0.12065 -0.2794)
			(stroke
				(width 0.1)
				(type default)
			)
			(layer "B.Fab")
		)
		(fp_line
			(start -0.67945 -0.3048)
			(end -0.67945 0.3048)
			(stroke
				(width 0.1)
				(type default)
			)
			(layer "B.Fab")
		)
		(fp_line
			(start -0.12065 -0.3048)
			(end -0.67945 -0.3048)
			(stroke
				(width 0.1)
				(type default)
			)
			(layer "B.Fab")
		)
		(fp_line
			(start 0.12065 -0.305054)
			(end 0.12065 -0.2794)
			(stroke
				(width 0.1)
				(type default)
			)
			(layer "B.Fab")
		)
		(fp_line
			(start 0.67945 -0.305054)
			(end 0.12065 -0.305054)
			(stroke
				(width 0.1)
				(type default)
			)
			(layer "B.Fab")
		)
		(pad "1" smd circle
			(at 0.40005 0 90)
			(size 0 0)
			(layers "B.Cu" "B.Mask" "B.Paste")
			(net "NC_PVDDCR_CPU0_P1_IMON9")
		)
		(pad "2" smd circle
			(at -0.40005 0 90)
			(size 0 0)
			(layers "B.Cu" "B.Mask" "B.Paste")
			(net "GND")
		)
	)
	(footprint ""
		(layer "B.Cu")
		(at 402.466302 -152.29078 -90)
		(property "Reference" "R4641"
			(at 0 0 90)
			(layer "B.SilkS")
			(hide yes)
			(effects
				(font
					(size 1.27 1.27)
				)
				(justify mirror)
			)
		)
		(property "Value" ""
			(at 0 0 90)
			(layer "B.Fab")
			(effects
				(font
					(size 1.27 1.27)
				)
				(justify mirror)
			)
		)
		(duplicate_pad_numbers_are_jumpers no)
		(fp_line
			(start -2.234946 0.9271)
			(end 2.234946 0.9271)
			(stroke
				(width 0.1524)
				(type default)
			)
			(layer "B.SilkS")
		)
		(fp_line
			(start 2.234946 0.9271)
			(end 2.234946 -0.9271)
			(stroke
				(width 0.1524)
				(type default)
			)
			(layer "B.SilkS")
		)
		(fp_line
			(start -2.234946 -0.9271)
			(end -2.234946 0.9271)
			(stroke
				(width 0.1524)
				(type default)
			)
			(layer "B.SilkS")
		)
		(fp_line
			(start 2.234946 -0.9271)
			(end -2.234946 -0.9271)
			(stroke
				(width 0.1524)
				(type default)
			)
			(layer "B.SilkS")
		)
		(fp_line
			(start -1.575054 0.824992)
			(end -1.575054 -0.824992)
			(stroke
				(width 0.1)
				(type default)
			)
			(layer "B.Fab")
		)
		(fp_line
			(start 1.575054 0.824992)
			(end -1.575054 0.824992)
			(stroke
				(width 0.1)
				(type default)
			)
			(layer "B.Fab")
		)
		(fp_line
			(start -1.575054 -0.824992)
			(end 1.575054 -0.824992)
			(stroke
				(width 0.1)
				(type default)
			)
			(layer "B.Fab")
		)
		(fp_line
			(start 1.575054 -0.824992)
			(end 1.575054 0.824992)
			(stroke
				(width 0.1)
				(type default)
			)
			(layer "B.Fab")
		)
		(pad "1" smd rect
			(at 1.599946 0 90)
			(size 1.016 1.6002)
			(layers "B.Cu" "B.Mask" "B.Paste")
			(net "P5V")
		)
		(pad "2" smd rect
			(at -1.599946 0 90)
			(size 1.016 1.6002)
			(layers "B.Cu" "B.Mask" "B.Paste")
			(net "VR_P5V_EN_D")
		)
	)
	(footprint ""
		(layer "B.Cu")
		(at 13.622782 -415.644584 -90)
		(property "Reference" "PR6542"
			(at 0 0 90)
			(layer "B.SilkS")
			(hide yes)
			(effects
				(font
					(size 1.27 1.27)
				)
				(justify mirror)
			)
		)
		(property "Value" ""
			(at 0 0 90)
			(layer "B.Fab")
			(effects
				(font
					(size 1.27 1.27)
				)
				(justify mirror)
			)
		)
		(duplicate_pad_numbers_are_jumpers no)
		(fp_line
			(start -0.7874 0.4064)
			(end 0.7874 0.4064)
			(stroke
				(width 0.1524)
				(type default)
			)
			(layer "B.SilkS")
		)
		(fp_line
			(start 0.7874 0.4064)
			(end 0.7874 -0.4064)
			(stroke
				(width 0.1524)
				(type default)
			)
			(layer "B.SilkS")
		)
		(fp_line
			(start -0.7874 -0.4064)
			(end -0.7874 0.4064)
			(stroke
				(width 0.1524)
				(type default)
			)
			(layer "B.SilkS")
		)
		(fp_line
			(start 0.7874 -0.4064)
			(end -0.7874 -0.4064)
			(stroke
				(width 0.1524)
				(type default)
			)
			(layer "B.SilkS")
		)
		(fp_line
			(start -0.67945 0.3048)
			(end -0.120396 0.3048)
			(stroke
				(width 0.1)
				(type default)
			)
			(layer "B.Fab")
		)
		(fp_line
			(start -0.120396 0.3048)
			(end -0.120396 0.2794)
			(stroke
				(width 0.1)
				(type default)
			)
			(layer "B.Fab")
		)
		(fp_line
			(start 0.12065 0.3048)
			(end 0.67945 0.3048)
			(stroke
				(width 0.1)
				(type default)
			)
			(layer "B.Fab")
		)
		(fp_line
			(start 0.67945 0.3048)
			(end 0.67945 -0.305054)
			(stroke
				(width 0.1)
				(type default)
			)
			(layer "B.Fab")
		)
		(fp_line
			(start -0.120396 0.2794)
			(end 0.12065 0.2794)
			(stroke
				(width 0.1)
				(type default)
			)
			(layer "B.Fab")
		)
		(fp_line
			(start 0.12065 0.2794)
			(end 0.12065 0.3048)
			(stroke
				(width 0.1)
				(type default)
			)
			(layer "B.Fab")
		)
		(fp_line
			(start -0.12065 -0.2794)
			(end -0.12065 -0.3048)
			(stroke
				(width 0.1)
				(type default)
			)
			(layer "B.Fab")
		)
		(fp_line
			(start 0.12065 -0.2794)
			(end -0.12065 -0.2794)
			(stroke
				(width 0.1)
				(type default)
			)
			(layer "B.Fab")
		)
		(fp_line
			(start -0.67945 -0.3048)
			(end -0.67945 0.3048)
			(stroke
				(width 0.1)
				(type default)
			)
			(layer "B.Fab")
		)
		(fp_line
			(start -0.12065 -0.3048)
			(end -0.67945 -0.3048)
			(stroke
				(width 0.1)
				(type default)
			)
			(layer "B.Fab")
		)
		(fp_line
			(start 0.12065 -0.305054)
			(end 0.12065 -0.2794)
			(stroke
				(width 0.1)
				(type default)
			)
			(layer "B.Fab")
		)
		(fp_line
			(start 0.67945 -0.305054)
			(end 0.12065 -0.305054)
			(stroke
				(width 0.1)
				(type default)
			)
			(layer "B.Fab")
		)
		(pad "1" smd circle
			(at 0.40005 0 90)
			(size 0 0)
			(layers "B.Cu" "B.Mask" "B.Paste")
			(net "NC_P0V9_RETIMER_CPU1_IMON6")
		)
		(pad "2" smd circle
			(at -0.40005 0 90)
			(size 0 0)
			(layers "B.Cu" "B.Mask" "B.Paste")
			(net "GND")
		)
	)
)
